FILE_TYPE=LIBRARY_PARTS;
primitive 'M24128BWDW6TP';
  pin
    'VCC':
      PIN_NUMBER='(8)';
      PINUSE='POWER';
      NO_LOAD_CHECK='Both';
      NO_IO_CHECK='Both';
      NO_ASSERT_CHECK='TRUE';
      NO_DIR_CHECK='TRUE';
      ALLOW_CONNECT='TRUE';
    'WC#':
      PIN_NUMBER='(7)';
      INPUT_LOAD='(-0.01,0.01)';
    'SCL':
      PIN_NUMBER='(6)';
      INPUT_LOAD='(-0.01,0.01)';
    'SDA':
      PIN_NUMBER='(5)';
      BIDIRECTIONAL='TRUE';
      INPUT_LOAD='(-0.01,0.01)';
      OUTPUT_LOAD='(1.0,-1.0)';
    'VSS':
      PIN_NUMBER='(4)';
      PINUSE='POWER';
      NO_LOAD_CHECK='Both';
      NO_IO_CHECK='Both';
      NO_ASSERT_CHECK='TRUE';
      NO_DIR_CHECK='TRUE';
      ALLOW_CONNECT='TRUE';
    'E2':
      PIN_NUMBER='(3)';
      INPUT_LOAD='(-0.01,0.01)';
    'E1':
      PIN_NUMBER='(2)';
      INPUT_LOAD='(-0.01,0.01)';
    'E0':
      PIN_NUMBER='(1)';
      INPUT_LOAD='(-0.01,0.01)';
  end_pin;
  body
    PART_NAME='M24128BWDW6TP';
    BODY_NAME='M24128BWDW6TP';
    PHYS_DES_PREFIX='U';
    CLASS='IC';
  end_body;
end_primitive;

END.
